(kicad_pcb
	(version 20260206)
	(generator "pcbnew")
	(generator_version "10.0")
	(general
		(thickness 1.6)
		(legacy_teardrops no)
	)
	(paper "A4")
	(title_block
		(title "dpb — 14545-sa.0730WZS0815.brd")
		(comment 1 "Honey Badger (Wiwynn) / footprints 888-894 of 1066")
	)
	(layers
		(0 "F.Cu" signal "TOP")
		(4 "In1.Cu" signal "L2GND")
		(6 "In2.Cu" signal "L3")
		(8 "In3.Cu" signal "L4VCC")
		(10 "In4.Cu" signal "L5VCC")
		(12 "In5.Cu" signal "L6")
		(14 "In6.Cu" signal "L7GND")
		(2 "B.Cu" signal "BOTTOM")
		(9 "F.Adhes" user "F.Adhesive")
		(11 "B.Adhes" user "B.Adhesive")
		(13 "F.Paste" user "Package Geometry/Pastemask Top")
		(15 "B.Paste" user "Package Geometry/Pastemask Bottom")
		(5 "F.SilkS" user "Ref Des/Silkscreen Top")
		(7 "B.SilkS" user "Ref Des/Silkscreen Bottom")
		(1 "F.Mask" user "Board Geometry/Soldermask Top")
		(3 "B.Mask" user "Board Geometry/Soldermask Bottom")
		(17 "Dwgs.User" user "User.Drawings")
		(19 "Cmts.User" user "User.Comments")
		(21 "Eco1.User" user "User.Eco1")
		(23 "Eco2.User" user "User.Eco2")
		(25 "Edge.Cuts" user "Board Geometry/Outline")
		(27 "Margin" user)
		(31 "F.CrtYd" user "Package Geometry/Place Bound Top")
		(29 "B.CrtYd" user "Package Geometry/Place Bound Bottom")
		(35 "F.Fab" user "Ref Des/Assembly Top")
		(33 "B.Fab" user "Ref Des/Assembly Bottom")
	)
	(footprint ""
		(layer "F.Cu")
		(at 41.147746 -110.645702 -90)
		(property "Reference" "Q28"
			(at 0 0 270)
			(layer "F.SilkS")
			(hide yes)
			(effects
				(font
					(size 1.27 1.27)
				)
			)
		)
		(property "Value" "2N7002DW-7F-GP"
			(at -2.3622 -8.2042 270)
			(unlocked yes)
			(layer "F.Fab")
			(hide yes)
			(effects
				(font
					(size 1.016 1.016)
					(thickness 0.1524)
				)
			)
		)
		(property "Device Type" "SOT-363H44"
			(at -2.3622 -10.1092 270)
			(unlocked yes)
			(layer "F.Fab")
			(hide yes)
			(effects
				(font
					(size 1.016 1.016)
					(thickness 0.1524)
				)
			)
		)
		(duplicate_pad_numbers_are_jumpers no)
		(fp_line
			(start -1.4478 1.7018)
			(end 1.4478 1.7018)
			(stroke
				(width 0.1524)
				(type default)
			)
			(layer "F.SilkS")
		)
		(fp_line
			(start 1.4478 1.7018)
			(end 1.4478 -1.7018)
			(stroke
				(width 0.1524)
				(type default)
			)
			(layer "F.SilkS")
		)
		(fp_line
			(start -1.27 1.524)
			(end -1.27 0.6604)
			(stroke
				(width 0.4826)
				(type default)
			)
			(layer "F.SilkS")
		)
		(fp_line
			(start -1.4478 -1.7018)
			(end -1.4478 1.7018)
			(stroke
				(width 0.1524)
				(type default)
			)
			(layer "F.SilkS")
		)
		(fp_line
			(start 1.4478 -1.7018)
			(end -1.4478 -1.7018)
			(stroke
				(width 0.1524)
				(type default)
			)
			(layer "F.SilkS")
		)
		(fp_poly
			(pts
				(xy -1.524 -1.778) (xy 1.524 -1.778) (xy 1.524 1.778) (xy -1.524 1.778)
			)
			(stroke
				(width 0)
				(type default)
			)
			(fill no)
			(layer "F.CrtYd")
		)
		(fp_poly
			(pts
				(xy -1.524 -1.778) (xy 1.524 -1.778) (xy 1.524 1.778) (xy -1.524 1.778)
			)
			(stroke
				(width 0)
				(type default)
			)
			(fill no)
			(layer "F.Fab")
		)
		(pad "1" smd rect
			(at -0.65024 0.9398 270)
			(size 0.4064 1.016)
			(layers "F.Cu" "F.Mask" "F.Paste")
			(net "GND")
		)
		(pad "2" smd rect
			(at 0 0.9398 270)
			(size 0.4064 1.016)
			(layers "F.Cu" "F.Mask" "F.Paste")
			(net "SW_PWR_R_HDD13")
		)
		(pad "3" smd rect
			(at 0.65024 0.9398 270)
			(size 0.4064 1.016)
			(layers "F.Cu" "F.Mask" "F.Paste")
			(net "SW_HDD13_P")
		)
		(pad "4" smd rect
			(at 0.65024 -0.9398 270)
			(size 0.4064 1.016)
			(layers "F.Cu" "F.Mask" "F.Paste")
			(net "GND")
		)
		(pad "5" smd rect
			(at 0 -0.9398 270)
			(size 0.4064 1.016)
			(layers "F.Cu" "F.Mask" "F.Paste")
			(net "SW_HDD13_G")
		)
		(pad "6" smd rect
			(at -0.65024 -0.9398 270)
			(size 0.4064 1.016)
			(layers "F.Cu" "F.Mask" "F.Paste")
			(net "SW_HDD13_R")
		)
	)
	(footprint ""
		(layer "F.Cu")
		(at 191.472058 -392.505184 180)
		(property "Reference" "R126"
			(at 0 0 180)
			(layer "F.SilkS")
			(hide yes)
			(effects
				(font
					(size 1.27 1.27)
				)
			)
		)
		(property "Value" "0R2J-2-GP"
			(at 0.064008 -3.993896 180)
			(unlocked yes)
			(layer "F.Fab")
			(hide yes)
			(effects
				(font
					(size 1.016 1.016)
					(thickness 0.1524)
				)
			)
		)
		(property "Device Type" "R402H16"
			(at 0.064008 -5.517896 180)
			(unlocked yes)
			(layer "F.Fab")
			(hide yes)
			(effects
				(font
					(size 1.016 1.016)
					(thickness 0.1524)
				)
			)
		)
		(duplicate_pad_numbers_are_jumpers no)
		(fp_line
			(start 0.508 -0.9398)
			(end -0.508 -0.9398)
			(stroke
				(width 0.1524)
				(type default)
			)
			(layer "F.SilkS")
		)
		(fp_line
			(start -0.508 -0.9398)
			(end -0.508 0.9398)
			(stroke
				(width 0.1524)
				(type default)
			)
			(layer "F.SilkS")
		)
		(fp_rect
			(start -0.508 0.9398)
			(end 0.508 -0.9398)
			(stroke
				(width 0)
				(type default)
			)
			(fill no)
			(layer "F.CrtYd")
		)
		(fp_rect
			(start -0.508 0.9398)
			(end 0.508 -0.9398)
			(stroke
				(width 0)
				(type default)
			)
			(fill no)
			(layer "F.Fab")
		)
		(pad "1" smd custom
			(at 0 -0.4445 180)
			(size 0.1397 0.1397)
			(layers "F.Cu" "F.Mask" "F.Paste")
			(net "SW_PWR_HDD1")
			(options
				(clearance outline)
				(anchor circle)
			)
			(primitives
				(gr_poly
					(pts
						(arc
							(start -0.1778 -0.2794)
							(mid -0.249642 -0.249642)
							(end -0.2794 -0.1778)
						)
						(arc
							(start -0.2794 0.1778)
							(mid -0.249642 0.249642)
							(end -0.1778 0.2794)
						)
						(arc
							(start 0.1778 0.2794)
							(mid 0.249642 0.249642)
							(end 0.2794 0.1778)
						)
						(arc
							(start 0.2794 -0.1778)
							(mid 0.249642 -0.249642)
							(end 0.1778 -0.2794)
						)
					)
					(width 0)
					(fill yes)
				)
			)
		)
		(pad "2" smd custom
			(at 0 0.4445 180)
			(size 0.1397 0.1397)
			(layers "F.Cu" "F.Mask" "F.Paste")
			(net "SW_PWR_R_HDD1")
			(options
				(clearance outline)
				(anchor circle)
			)
			(primitives
				(gr_poly
					(pts
						(arc
							(start -0.1778 -0.2794)
							(mid -0.249642 -0.249642)
							(end -0.2794 -0.1778)
						)
						(arc
							(start -0.2794 0.1778)
							(mid -0.249642 0.249642)
							(end -0.1778 0.2794)
						)
						(arc
							(start 0.1778 0.2794)
							(mid 0.249642 0.249642)
							(end 0.2794 0.1778)
						)
						(arc
							(start 0.2794 -0.1778)
							(mid 0.249642 -0.249642)
							(end 0.1778 -0.2794)
						)
					)
					(width 0)
					(fill yes)
				)
			)
		)
	)
	(footprint ""
		(layer "F.Cu")
		(at 214.933784 -173.198028 90)
		(property "Reference" "R150"
			(at 0 0 90)
			(layer "F.SilkS")
			(hide yes)
			(effects
				(font
					(size 1.27 1.27)
				)
			)
		)
		(property "Value" "4K7R2J-2-GP"
			(at 0.064008 -3.993896 90)
			(unlocked yes)
			(layer "F.Fab")
			(hide yes)
			(effects
				(font
					(size 1.016 1.016)
					(thickness 0.1524)
				)
			)
		)
		(property "Device Type" "R402H16"
			(at 0.064008 -5.517896 90)
			(unlocked yes)
			(layer "F.Fab")
			(hide yes)
			(effects
				(font
					(size 1.016 1.016)
					(thickness 0.1524)
				)
			)
		)
		(duplicate_pad_numbers_are_jumpers no)
		(fp_line
			(start 0.508 -0.9398)
			(end -0.508 -0.9398)
			(stroke
				(width 0.1524)
				(type default)
			)
			(layer "F.SilkS")
		)
		(fp_line
			(start -0.508 -0.9398)
			(end -0.508 0.9398)
			(stroke
				(width 0.1524)
				(type default)
			)
			(layer "F.SilkS")
		)
		(fp_rect
			(start -0.508 0.9398)
			(end 0.508 -0.9398)
			(stroke
				(width 0)
				(type default)
			)
			(fill no)
			(layer "F.CrtYd")
		)
		(fp_rect
			(start -0.508 0.9398)
			(end 0.508 -0.9398)
			(stroke
				(width 0)
				(type default)
			)
			(fill no)
			(layer "F.Fab")
		)
		(pad "1" smd custom
			(at 0 -0.4445 90)
			(size 0.1397 0.1397)
			(layers "F.Cu" "F.Mask" "F.Paste")
			(net "P3V3")
			(options
				(clearance outline)
				(anchor circle)
			)
			(primitives
				(gr_poly
					(pts
						(arc
							(start -0.1778 -0.2794)
							(mid -0.249642 -0.249642)
							(end -0.2794 -0.1778)
						)
						(arc
							(start -0.2794 0.1778)
							(mid -0.249642 0.249642)
							(end -0.1778 0.2794)
						)
						(arc
							(start 0.1778 0.2794)
							(mid 0.249642 0.249642)
							(end 0.2794 0.1778)
						)
						(arc
							(start 0.2794 -0.1778)
							(mid 0.249642 -0.249642)
							(end 0.1778 -0.2794)
						)
					)
					(width 0)
					(fill yes)
				)
			)
		)
		(pad "2" smd custom
			(at 0 0.4445 90)
			(size 0.1397 0.1397)
			(layers "F.Cu" "F.Mask" "F.Paste")
			(net "HDD_PRSNT_NET3")
			(options
				(clearance outline)
				(anchor circle)
			)
			(primitives
				(gr_poly
					(pts
						(arc
							(start -0.1778 -0.2794)
							(mid -0.249642 -0.249642)
							(end -0.2794 -0.1778)
						)
						(arc
							(start -0.2794 0.1778)
							(mid -0.249642 0.249642)
							(end -0.1778 0.2794)
						)
						(arc
							(start 0.1778 0.2794)
							(mid 0.249642 0.249642)
							(end 0.2794 0.1778)
						)
						(arc
							(start 0.2794 -0.1778)
							(mid 0.249642 -0.249642)
							(end 0.1778 -0.2794)
						)
					)
					(width 0)
					(fill yes)
				)
			)
		)
	)
	(footprint ""
		(layer "F.Cu")
		(at 46.017688 -21.989288 -90)
		(property "Reference" "PR32"
			(at 0 0 270)
			(layer "F.SilkS")
			(hide yes)
			(effects
				(font
					(size 1.27 1.27)
				)
			)
		)
		(property "Value" "0R2J-2-GP"
			(at 0.064008 -3.993896 270)
			(unlocked yes)
			(layer "F.Fab")
			(hide yes)
			(effects
				(font
					(size 1.016 1.016)
					(thickness 0.1524)
				)
			)
		)
		(property "Device Type" "R402H16"
			(at 0.064008 -5.517896 270)
			(unlocked yes)
			(layer "F.Fab")
			(hide yes)
			(effects
				(font
					(size 1.016 1.016)
					(thickness 0.1524)
				)
			)
		)
		(duplicate_pad_numbers_are_jumpers no)
		(fp_line
			(start -0.508 -0.9398)
			(end -0.508 0.9398)
			(stroke
				(width 0.1524)
				(type default)
			)
			(layer "F.SilkS")
		)
		(fp_line
			(start 0.508 -0.9398)
			(end -0.508 -0.9398)
			(stroke
				(width 0.1524)
				(type default)
			)
			(layer "F.SilkS")
		)
		(fp_rect
			(start -0.508 0.9398)
			(end 0.508 -0.9398)
			(stroke
				(width 0)
				(type default)
			)
			(fill no)
			(layer "F.CrtYd")
		)
		(fp_rect
			(start -0.508 0.9398)
			(end 0.508 -0.9398)
			(stroke
				(width 0)
				(type default)
			)
			(fill no)
			(layer "F.Fab")
		)
		(pad "1" smd custom
			(at 0 -0.4445 270)
			(size 0.1397 0.1397)
			(layers "F.Cu" "F.Mask" "F.Paste")
			(net "P5VB_ROVP")
			(options
				(clearance outline)
				(anchor circle)
			)
			(primitives
				(gr_poly
					(pts
						(arc
							(start -0.1778 -0.2794)
							(mid -0.249642 -0.249642)
							(end -0.2794 -0.1778)
						)
						(arc
							(start -0.2794 0.1778)
							(mid -0.249642 0.249642)
							(end -0.1778 0.2794)
						)
						(arc
							(start 0.1778 0.2794)
							(mid 0.249642 0.249642)
							(end 0.2794 0.1778)
						)
						(arc
							(start 0.2794 -0.1778)
							(mid 0.249642 -0.249642)
							(end 0.1778 -0.2794)
						)
					)
					(width 0)
					(fill yes)
				)
			)
		)
		(pad "2" smd custom
			(at 0 0.4445 270)
			(size 0.1397 0.1397)
			(layers "F.Cu" "F.Mask" "F.Paste")
			(net "P5VB_AGND")
			(options
				(clearance outline)
				(anchor circle)
			)
			(primitives
				(gr_poly
					(pts
						(arc
							(start -0.1778 -0.2794)
							(mid -0.249642 -0.249642)
							(end -0.2794 -0.1778)
						)
						(arc
							(start -0.2794 0.1778)
							(mid -0.249642 0.249642)
							(end -0.1778 0.2794)
						)
						(arc
							(start 0.1778 0.2794)
							(mid 0.249642 0.249642)
							(end 0.2794 0.1778)
						)
						(arc
							(start 0.2794 -0.1778)
							(mid 0.249642 -0.249642)
							(end 0.1778 -0.2794)
						)
					)
					(width 0)
					(fill yes)
				)
			)
		)
	)
	(footprint ""
		(layer "F.Cu")
		(at 33.02 -345.694 -90)
		(property "Reference" "R255"
			(at 0 0 270)
			(layer "F.SilkS")
			(hide yes)
			(effects
				(font
					(size 1.27 1.27)
				)
			)
		)
		(property "Value" "402R2F-GP"
			(at 0.064008 -3.993896 270)
			(unlocked yes)
			(layer "F.Fab")
			(hide yes)
			(effects
				(font
					(size 1.016 1.016)
					(thickness 0.1524)
				)
			)
		)
		(property "Device Type" "R402H16"
			(at 0.064008 -5.517896 270)
			(unlocked yes)
			(layer "F.Fab")
			(hide yes)
			(effects
				(font
					(size 1.016 1.016)
					(thickness 0.1524)
				)
			)
		)
		(duplicate_pad_numbers_are_jumpers no)
		(fp_line
			(start -0.508 -0.9398)
			(end -0.508 0.9398)
			(stroke
				(width 0.1524)
				(type default)
			)
			(layer "F.SilkS")
		)
		(fp_line
			(start 0.508 -0.9398)
			(end -0.508 -0.9398)
			(stroke
				(width 0.1524)
				(type default)
			)
			(layer "F.SilkS")
		)
		(fp_rect
			(start -0.508 0.9398)
			(end 0.508 -0.9398)
			(stroke
				(width 0)
				(type default)
			)
			(fill no)
			(layer "F.CrtYd")
		)
		(fp_rect
			(start -0.508 0.9398)
			(end 0.508 -0.9398)
			(stroke
				(width 0)
				(type default)
			)
			(fill no)
			(layer "F.Fab")
		)
		(pad "1" smd custom
			(at 0 -0.4445 270)
			(size 0.1397 0.1397)
			(layers "F.Cu" "F.Mask" "F.Paste")
			(net "P5VC_HDD11_LED")
			(options
				(clearance outline)
				(anchor circle)
			)
			(primitives
				(gr_poly
					(pts
						(arc
							(start -0.1778 -0.2794)
							(mid -0.249642 -0.249642)
							(end -0.2794 -0.1778)
						)
						(arc
							(start -0.2794 0.1778)
							(mid -0.249642 0.249642)
							(end -0.1778 0.2794)
						)
						(arc
							(start 0.1778 0.2794)
							(mid 0.249642 0.249642)
							(end 0.2794 0.1778)
						)
						(arc
							(start 0.2794 -0.1778)
							(mid 0.249642 -0.249642)
							(end 0.1778 -0.2794)
						)
					)
					(width 0)
					(fill yes)
				)
			)
		)
		(pad "2" smd custom
			(at 0 0.4445 270)
			(size 0.1397 0.1397)
			(layers "F.Cu" "F.Mask" "F.Paste")
			(net "DRV_ACT_11")
			(options
				(clearance outline)
				(anchor circle)
			)
			(primitives
				(gr_poly
					(pts
						(arc
							(start -0.1778 -0.2794)
							(mid -0.249642 -0.249642)
							(end -0.2794 -0.1778)
						)
						(arc
							(start -0.2794 0.1778)
							(mid -0.249642 0.249642)
							(end -0.1778 0.2794)
						)
						(arc
							(start 0.1778 0.2794)
							(mid 0.249642 0.249642)
							(end 0.2794 0.1778)
						)
						(arc
							(start 0.2794 -0.1778)
							(mid 0.249642 -0.249642)
							(end 0.1778 -0.2794)
						)
					)
					(width 0)
					(fill yes)
				)
			)
		)
	)
	(footprint ""
		(layer "F.Cu")
		(at 41.401746 -217.325702)
		(property "Reference" "C307"
			(at 0 0 0)
			(layer "F.SilkS")
			(hide yes)
			(effects
				(font
					(size 1.27 1.27)
				)
			)
		)
		(property "Value" "SC1U25V3KX-1-GP"
			(at 0 -2.8194 0)
			(unlocked yes)
			(layer "F.Fab")
			(hide yes)
			(effects
				(font
					(size 1.016 1.016)
					(thickness 0.1524)
				)
			)
		)
		(property "Device Type" "C603H36"
			(at 0 -4.3434 0)
			(unlocked yes)
			(layer "F.Fab")
			(hide yes)
			(effects
				(font
					(size 1.016 1.016)
					(thickness 0.1524)
				)
			)
		)
		(duplicate_pad_numbers_are_jumpers no)
		(fp_line
			(start 0.508 0)
			(end -0.508 0)
			(stroke
				(width 0.2032)
				(type default)
			)
			(layer "F.SilkS")
		)
		(fp_rect
			(start -0.5842 1.3335)
			(end 0.5842 -1.3335)
			(stroke
				(width 0)
				(type default)
			)
			(fill no)
			(layer "F.CrtYd")
		)
		(fp_rect
			(start -0.5842 1.3335)
			(end 0.5842 -1.3335)
			(stroke
				(width 0)
				(type default)
			)
			(fill no)
			(layer "F.Fab")
		)
		(pad "1" smd custom
			(at 0 -0.762)
			(size 0.2159 0.2159)
			(layers "F.Cu" "F.Mask" "F.Paste")
			(net "P12V_HDD12")
			(options
				(clearance outline)
				(anchor circle)
			)
			(primitives
				(gr_poly
					(pts
						(arc
							(start -0.3302 -0.4318)
							(mid -0.402042 -0.402042)
							(end -0.4318 -0.3302)
						)
						(arc
							(start -0.4318 0.3302)
							(mid -0.402042 0.402042)
							(end -0.3302 0.4318)
						)
						(arc
							(start 0.3302 0.4318)
							(mid 0.402042 0.402042)
							(end 0.4318 0.3302)
						)
						(arc
							(start 0.4318 -0.3302)
							(mid 0.402042 -0.402042)
							(end 0.3302 -0.4318)
						)
					)
					(width 0)
					(fill yes)
				)
			)
		)
		(pad "2" smd custom
			(at 0 0.762)
			(size 0.2159 0.2159)
			(layers "F.Cu" "F.Mask" "F.Paste")
			(net "GND")
			(options
				(clearance outline)
				(anchor circle)
			)
			(primitives
				(gr_poly
					(pts
						(arc
							(start -0.3302 -0.4318)
							(mid -0.402042 -0.402042)
							(end -0.4318 -0.3302)
						)
						(arc
							(start -0.4318 0.3302)
							(mid -0.402042 0.402042)
							(end -0.3302 0.4318)
						)
						(arc
							(start 0.3302 0.4318)
							(mid 0.402042 0.402042)
							(end 0.4318 0.3302)
						)
						(arc
							(start 0.4318 -0.3302)
							(mid 0.402042 -0.402042)
							(end 0.3302 -0.4318)
						)
					)
					(width 0)
					(fill yes)
				)
			)
		)
	)
	(footprint ""
		(layer "F.Cu")
		(at 194.31 -498.475 180)
		(property "Reference" "R563"
			(at 0 0 180)
			(layer "F.SilkS")
			(hide yes)
			(effects
				(font
					(size 1.27 1.27)
				)
			)
		)
		(property "Value" "300KR2F-GP"
			(at 0.064008 -3.993896 180)
			(unlocked yes)
			(layer "F.Fab")
			(hide yes)
			(effects
				(font
					(size 1.016 1.016)
					(thickness 0.1524)
				)
			)
		)
		(property "Device Type" "R402H16"
			(at 0.064008 -5.517896 180)
			(unlocked yes)
			(layer "F.Fab")
			(hide yes)
			(effects
				(font
					(size 1.016 1.016)
					(thickness 0.1524)
				)
			)
		)
		(duplicate_pad_numbers_are_jumpers no)
		(fp_line
			(start 0.508 -0.9398)
			(end -0.508 -0.9398)
			(stroke
				(width 0.1524)
				(type default)
			)
			(layer "F.SilkS")
		)
		(fp_line
			(start -0.508 -0.9398)
			(end -0.508 0.9398)
			(stroke
				(width 0.1524)
				(type default)
			)
			(layer "F.SilkS")
		)
		(fp_rect
			(start -0.508 0.9398)
			(end 0.508 -0.9398)
			(stroke
				(width 0)
				(type default)
			)
			(fill no)
			(layer "F.CrtYd")
		)
		(fp_rect
			(start -0.508 0.9398)
			(end 0.508 -0.9398)
			(stroke
				(width 0)
				(type default)
			)
			(fill no)
			(layer "F.Fab")
		)
		(pad "1" smd custom
			(at 0 -0.4445 180)
			(size 0.1397 0.1397)
			(layers "F.Cu" "F.Mask" "F.Paste")
			(net "SW_HDD0_N")
			(options
				(clearance outline)
				(anchor circle)
			)
			(primitives
				(gr_poly
					(pts
						(arc
							(start -0.1778 -0.2794)
							(mid -0.249642 -0.249642)
							(end -0.2794 -0.1778)
						)
						(arc
							(start -0.2794 0.1778)
							(mid -0.249642 0.249642)
							(end -0.1778 0.2794)
						)
						(arc
							(start 0.1778 0.2794)
							(mid 0.249642 0.249642)
							(end 0.2794 0.1778)
						)
						(arc
							(start 0.2794 -0.1778)
							(mid 0.249642 -0.249642)
							(end 0.1778 -0.2794)
						)
					)
					(width 0)
					(fill yes)
				)
			)
		)
		(pad "2" smd custom
			(at 0 0.4445 180)
			(size 0.1397 0.1397)
			(layers "F.Cu" "F.Mask" "F.Paste")
			(net "P12V")
			(options
				(clearance outline)
				(anchor circle)
			)
			(primitives
				(gr_poly
					(pts
						(arc
							(start -0.1778 -0.2794)
							(mid -0.249642 -0.249642)
							(end -0.2794 -0.1778)
						)
						(arc
							(start -0.2794 0.1778)
							(mid -0.249642 0.249642)
							(end -0.1778 0.2794)
						)
						(arc
							(start 0.1778 0.2794)
							(mid 0.249642 0.249642)
							(end 0.2794 0.1778)
						)
						(arc
							(start 0.2794 -0.1778)
							(mid 0.249642 -0.249642)
							(end 0.1778 -0.2794)
						)
					)
					(width 0)
					(fill yes)
				)
			)
		)
	)
)
